# BASEBOARD_FAB2 (Tioga Pass) — schematic netlist excerpt (pin names and nets, part order shuffled) for the footprints in the layout excerpt that follows; sources: Cadence DE-HDL packaged netlist, KiCad conversion of Wiwynn_Tioga_Pass_MB.brd

DS9E1  LED  IC  pkg A1LF  page 151 : A = FM_HEARTBEAT_LED_A ; C = FM_HEARTBEAT_LED_K
CF9  SC22P50V2JN-4GP  5%  pkg SMD-BCG  page 206 : \1\ = VR_PVCCIN_CPU1_AIREF3 ; \2\ = ISENSE_PVCCIN_CPU1_PH3_IMON

(kicad_pcb
	(version 20260206)
	(generator "pcbnew")
	(generator_version "10.0")
	(general
		(thickness 1.6)
		(legacy_teardrops no)
	)
	(paper "A4")
	(title_block
		(title "Wiwynn_Tioga_Pass_MB.brd")
		(comment 1 "Tioga Pass / footprints 6-7 of 4770")
	)
	(layers
		(0 "F.Cu" signal "TOP")
		(4 "In1.Cu" signal "L2GND")
		(6 "In2.Cu" signal "L3")
		(8 "In3.Cu" signal "L4GND")
		(10 "In4.Cu" signal "L5")
		(12 "In5.Cu" signal "L6GND")
		(14 "In6.Cu" signal "L7VCC")
		(16 "In7.Cu" signal "L8VCC")
		(18 "In8.Cu" signal "L9GND")
		(20 "In9.Cu" signal "L10")
		(22 "In10.Cu" signal "L11GND")
		(24 "In11.Cu" signal "L12")
		(26 "In12.Cu" signal "L13GND")
		(2 "B.Cu" signal "BOTTOM")
		(9 "F.Adhes" user "F.Adhesive")
		(11 "B.Adhes" user "B.Adhesive")
		(13 "F.Paste" user "Package Geometry/Pastemask Top")
		(15 "B.Paste" user "Package Geometry/Pastemask Bottom")
		(5 "F.SilkS" user "Ref Des/Silkscreen Top")
		(7 "B.SilkS" user "Ref Des/Silkscreen Bottom")
		(1 "F.Mask" user "Board Geometry/Soldermask Top")
		(3 "B.Mask" user "Board Geometry/Soldermask Bottom")
		(17 "Dwgs.User" user "User.Drawings")
		(19 "Cmts.User" user "User.Comments")
		(21 "Eco1.User" user "User.Eco1")
		(23 "Eco2.User" user "User.Eco2")
		(25 "Edge.Cuts" user "Board Geometry/Outline")
		(27 "Margin" user)
		(31 "F.CrtYd" user "Package Geometry/Place Bound Top")
		(29 "B.CrtYd" user "Package Geometry/Place Bound Bottom")
		(35 "F.Fab" user "Ref Des/Assembly Top")
		(33 "B.Fab" user "Ref Des/Assembly Bottom")
	)
	(footprint ""
		(layer "F.Cu")
		(at 453.898 -36.449)
		(property "Reference" "DS9E1"
			(at 0 0 0)
			(layer "F.SilkS")
			(hide yes)
			(effects
				(font
					(size 1.27 1.27)
				)
			)
		)
		(property "Value" ""
			(at 0 0 0)
			(layer "F.Fab")
			(effects
				(font
					(size 1.27 1.27)
				)
			)
		)
		(duplicate_pad_numbers_are_jumpers no)
		(fp_line
			(start -1.985772 0.486918)
			(end -1.50495 0.486918)
			(stroke
				(width 0.1524)
				(type default)
			)
			(layer "F.SilkS")
		)
		(fp_line
			(start -1.985772 1.319784)
			(end -1.024128 1.319784)
			(stroke
				(width 0.1524)
				(type default)
			)
			(layer "F.SilkS")
		)
		(fp_line
			(start -1.50495 -0.424688)
			(end -1.50495 0.486918)
			(stroke
				(width 0.1524)
				(type default)
			)
			(layer "F.SilkS")
		)
		(fp_line
			(start -1.50495 0.486918)
			(end -1.024128 0.486918)
			(stroke
				(width 0.1524)
				(type default)
			)
			(layer "F.SilkS")
		)
		(fp_line
			(start -1.50495 1.319784)
			(end -1.985772 0.486918)
			(stroke
				(width 0.1524)
				(type default)
			)
			(layer "F.SilkS")
		)
		(fp_line
			(start -1.50495 2.443226)
			(end -1.50495 1.319784)
			(stroke
				(width 0.1524)
				(type default)
			)
			(layer "F.SilkS")
		)
		(fp_line
			(start -1.024128 0.486918)
			(end -1.50495 1.319784)
			(stroke
				(width 0.1524)
				(type default)
			)
			(layer "F.SilkS")
		)
		(fp_poly
			(pts
				(xy 0.6223 2.032) (xy -0.6223 2.032) (xy -0.6223 0.0254) (xy 0.6223 0.0254)
			)
			(stroke
				(width 0)
				(type default)
			)
			(fill no)
			(layer "F.CrtYd")
		)
		(fp_line
			(start -1.985772 0.486918)
			(end -1.024128 0.486918)
			(stroke
				(width 0.1)
				(type default)
			)
			(layer "F.Fab")
		)
		(fp_line
			(start -1.985772 1.319784)
			(end -1.024128 1.319784)
			(stroke
				(width 0.1)
				(type default)
			)
			(layer "F.Fab")
		)
		(fp_line
			(start -1.50495 0.486918)
			(end -1.50495 -0.424688)
			(stroke
				(width 0.1)
				(type default)
			)
			(layer "F.Fab")
		)
		(fp_line
			(start -1.50495 1.319784)
			(end -1.985772 0.486918)
			(stroke
				(width 0.1)
				(type default)
			)
			(layer "F.Fab")
		)
		(fp_line
			(start -1.50495 1.319784)
			(end -1.50495 2.443226)
			(stroke
				(width 0.1)
				(type default)
			)
			(layer "F.Fab")
		)
		(fp_line
			(start -1.024128 0.486918)
			(end -1.50495 1.319784)
			(stroke
				(width 0.1)
				(type default)
			)
			(layer "F.Fab")
		)
		(fp_line
			(start -0.6223 0.0254)
			(end 0.6223 0.0254)
			(stroke
				(width 0.1)
				(type default)
			)
			(layer "F.Fab")
		)
		(fp_line
			(start -0.6223 2.032)
			(end -0.6223 0.0254)
			(stroke
				(width 0.1)
				(type default)
			)
			(layer "F.Fab")
		)
		(fp_line
			(start 0.6223 0.0254)
			(end 0.6223 2.032)
			(stroke
				(width 0.1)
				(type default)
			)
			(layer "F.Fab")
		)
		(fp_line
			(start 0.6223 2.032)
			(end -0.6223 2.032)
			(stroke
				(width 0.1)
				(type default)
			)
			(layer "F.Fab")
		)
		(pad "1" smd rect
			(at 0 0)
			(size 1.27 1.27)
			(layers "F.Cu" "F.Mask" "F.Paste")
			(net "FM_HEARTBEAT_LED_A")
		)
		(pad "2" smd rect
			(at 0 2.032)
			(size 1.27 1.27)
			(layers "F.Cu" "F.Mask" "F.Paste")
			(net "FM_HEARTBEAT_LED_K")
		)
		(zone
			(layer "F.Cu")
			(hatch none 0.5)
			(connect_pads
				(clearance 0)
			)
			(min_thickness 0.25)
			(keepout
				(tracks not_allowed)
				(vias allowed)
				(pads allowed)
				(copperpour not_allowed)
				(footprints allowed)
			)
			(placement
				(enabled no)
				(sheetname "")
			)
			(fill
				(thermal_gap 0.5)
				(thermal_bridge_width 0.5)
				(island_removal_mode 0)
			)
			(polygon
				(pts
					(xy 453.263 -35.052) (xy 454.533 -35.052) (xy 454.533 -35.814) (xy 453.263 -35.814)
				)
			)
		)
		(zone
			(layer "F.Cu")
			(hatch none 0.5)
			(connect_pads
				(clearance 0)
			)
			(min_thickness 0.25)
			(keepout
				(tracks allowed)
				(vias not_allowed)
				(pads allowed)
				(copperpour not_allowed)
				(footprints allowed)
			)
			(placement
				(enabled no)
				(sheetname "")
			)
			(fill
				(thermal_gap 0.5)
				(thermal_bridge_width 0.5)
				(island_removal_mode 0)
			)
			(polygon
				(pts
					(xy 453.263 -35.052) (xy 454.533 -35.052) (xy 454.533 -35.814) (xy 453.263 -35.814)
				)
			)
		)
	)
	(footprint ""
		(layer "F.Cu")
		(at 25.02916 -90.05824 180)
		(property "Reference" "CF9"
			(at 0 0 180)
			(layer "F.SilkS")
			(hide yes)
			(effects
				(font
					(size 1.27 1.27)
				)
			)
		)
		(property "Value" "*"
			(at 1.1811 -2.8194 180)
			(unlocked yes)
			(layer "F.Fab")
			(hide yes)
			(effects
				(font
					(size 1.27 1.016)
					(thickness 0.1524)
				)
			)
		)
		(property "Device Type" "SC22P50V2JN-4GP_SMD-BCG-SC22P5A"
			(at 1.1811 -4.3434 180)
			(unlocked yes)
			(layer "F.Fab")
			(hide yes)
			(effects
				(font
					(size 1.27 1.016)
					(thickness 0.1524)
				)
			)
		)
		(duplicate_pad_numbers_are_jumpers no)
		(fp_rect
			(start -0.4318 0.9525)
			(end 0.4318 -0.9525)
			(stroke
				(width 0)
				(type default)
			)
			(fill no)
			(layer "F.CrtYd")
		)
		(fp_rect
			(start -0.4318 0.9525)
			(end 0.4318 -0.9525)
			(stroke
				(width 0)
				(type default)
			)
			(fill no)
			(layer "F.Fab")
		)
		(pad "1" smd custom
			(at 0 -0.4445 180)
			(size 0.1524 0.1524)
			(layers "F.Cu" "F.Mask" "F.Paste")
			(net "VR_PVCCIN_CPU1_AIREF3")
			(options
				(clearance outline)
				(anchor circle)
			)
			(primitives
				(gr_poly
					(pts
						(arc
							(start 0.3048 -0.2032)
							(mid 0.275042 -0.275042)
							(end 0.2032 -0.3048)
						)
						(arc
							(start -0.2032 -0.3048)
							(mid -0.275042 -0.275042)
							(end -0.3048 -0.2032)
						)
						(arc
							(start -0.3048 0.2032)
							(mid -0.275042 0.275042)
							(end -0.2032 0.3048)
						)
						(arc
							(start 0.2032 0.3048)
							(mid 0.275042 0.275042)
							(end 0.3048 0.2032)
						)
					)
					(width 0)
					(fill yes)
				)
			)
		)
		(pad "2" smd custom
			(at 0 0.4445 180)
			(size 0.1524 0.1524)
			(layers "F.Cu" "F.Mask" "F.Paste")
			(net "ISENSE_PVCCIN_CPU1_PH3_IMON")
			(options
				(clearance outline)
				(anchor circle)
			)
			(primitives
				(gr_poly
					(pts
						(arc
							(start 0.3048 -0.2032)
							(mid 0.275042 -0.275042)
							(end 0.2032 -0.3048)
						)
						(arc
							(start -0.2032 -0.3048)
							(mid -0.275042 -0.275042)
							(end -0.3048 -0.2032)
						)
						(arc
							(start -0.3048 0.2032)
							(mid -0.275042 0.275042)
							(end -0.2032 0.3048)
						)
						(arc
							(start 0.2032 0.3048)
							(mid 0.275042 0.275042)
							(end 0.3048 0.2032)
						)
					)
					(width 0)
					(fill yes)
				)
			)
		)
	)
)
